# S9S_MB_2U (Grand Teton) — schematic netlist excerpt (pin names and nets, part order shuffled) for the footprints in the layout excerpt that follows; sources: Cadence DE-HDL packaged netlist, KiCad conversion of 03242023_DA0F0TMBIJ0_F0T_Motherboard_J_brd_V01_OCP.brd

C1927  Q_CAP  0.01UF 50V 10% X7R  pkg C0402  page 217 : A = P3V3_AUX_FPGA_VCCIO1 ; B = GND
R1440  Q_RES  10K 1% EMPTY  pkg 0402LF  page 220 : A = JTAG_PLD_TDO_R ; B = P3V3_AUX

(kicad_pcb
	(version 20260206)
	(generator "pcbnew")
	(generator_version "10.0")
	(general
		(thickness 1.6)
		(legacy_teardrops no)
	)
	(paper "A4")
	(title_block
		(title "03242023_DA0F0TMBIJ0_F0T_Motherboard_J_brd_V01_OCP.brd")
		(comment 1 "Grand Teton / footprints 5463-5464 of 6105")
	)
	(layers
		(0 "F.Cu" signal "TOP")
		(4 "In1.Cu" signal "GND")
		(6 "In2.Cu" signal "IN1")
		(8 "In3.Cu" signal "GND1")
		(10 "In4.Cu" signal "IN2")
		(12 "In5.Cu" signal "GND2")
		(14 "In6.Cu" signal "IN3")
		(16 "In7.Cu" signal "GND3")
		(18 "In8.Cu" signal "VCC")
		(20 "In9.Cu" signal "VCC1")
		(22 "In10.Cu" signal "GND4")
		(24 "In11.Cu" signal "IN4")
		(26 "In12.Cu" signal "GND5")
		(28 "In13.Cu" signal "IN5")
		(30 "In14.Cu" signal "GND6")
		(32 "In15.Cu" signal "IN6")
		(34 "In16.Cu" signal "GND7")
		(2 "B.Cu" signal "BOTTOM")
		(9 "F.Adhes" user "F.Adhesive")
		(11 "B.Adhes" user "B.Adhesive")
		(13 "F.Paste" user "Package Geometry/Pastemask Top")
		(15 "B.Paste" user "Package Geometry/Pastemask Bottom")
		(5 "F.SilkS" user "Ref Des/Silkscreen Top")
		(7 "B.SilkS" user "Ref Des/Silkscreen Bottom")
		(1 "F.Mask" user "Board Geometry/Soldermask Top")
		(3 "B.Mask" user "Board Geometry/Soldermask Bottom")
		(17 "Dwgs.User" user "User.Drawings")
		(19 "Cmts.User" user "User.Comments")
		(21 "Eco1.User" user "User.Eco1")
		(23 "Eco2.User" user "User.Eco2")
		(25 "Edge.Cuts" user "Board Geometry/Outline")
		(27 "Margin" user)
		(31 "F.CrtYd" user "Package Geometry/Place Bound Top")
		(29 "B.CrtYd" user "Package Geometry/Place Bound Bottom")
		(35 "F.Fab" user "Ref Des/Assembly Top")
		(33 "B.Fab" user "Ref Des/Assembly Bottom")
	)
	(footprint ""
		(layer "B.Cu")
		(at 178.1556 -115.775486 90)
		(property "Reference" "C1927"
			(at 0 0 90)
			(layer "B.SilkS")
			(hide yes)
			(effects
				(font
					(size 1.27 1.27)
				)
				(justify mirror)
			)
		)
		(property "Value" ""
			(at 0 0 90)
			(layer "B.Fab")
			(effects
				(font
					(size 1.27 1.27)
				)
				(justify mirror)
			)
		)
		(duplicate_pad_numbers_are_jumpers no)
		(fp_line
			(start 0.69215 -0.2921)
			(end -0.69215 -0.2921)
			(stroke
				(width 0.1524)
				(type default)
			)
			(layer "B.SilkS")
		)
		(fp_line
			(start -0.69215 -0.2921)
			(end -0.69215 0.2921)
			(stroke
				(width 0.1524)
				(type default)
			)
			(layer "B.SilkS")
		)
		(fp_line
			(start 0.69215 0.2921)
			(end 0.69215 -0.2921)
			(stroke
				(width 0.1524)
				(type default)
			)
			(layer "B.SilkS")
		)
		(fp_line
			(start -0.69215 0.2921)
			(end 0.69215 0.2921)
			(stroke
				(width 0.1524)
				(type default)
			)
			(layer "B.SilkS")
		)
		(fp_line
			(start 0.51435 -0.2794)
			(end -0.51435 -0.2794)
			(stroke
				(width 0.1)
				(type default)
			)
			(layer "B.Fab")
		)
		(fp_line
			(start -0.51435 -0.2794)
			(end -0.51435 0.2794)
			(stroke
				(width 0.1)
				(type default)
			)
			(layer "B.Fab")
		)
		(fp_line
			(start 0.51435 0.2794)
			(end 0.51435 -0.2794)
			(stroke
				(width 0.1)
				(type default)
			)
			(layer "B.Fab")
		)
		(fp_line
			(start -0.51435 0.2794)
			(end 0.51435 0.2794)
			(stroke
				(width 0.1)
				(type default)
			)
			(layer "B.Fab")
		)
		(pad "1" smd circle
			(at 0.40005 0 270)
			(size 0 0)
			(layers "B.Cu" "B.Mask" "B.Paste")
			(net "P3V3_AUX_FPGA_VCCIO1")
		)
		(pad "2" smd circle
			(at -0.40005 0 270)
			(size 0 0)
			(layers "B.Cu" "B.Mask" "B.Paste")
			(net "GND")
		)
		(zone
			(layer "B.Cu")
			(hatch none 0.5)
			(connect_pads
				(clearance 0)
			)
			(min_thickness 0.25)
			(keepout
				(tracks not_allowed)
				(vias allowed)
				(pads allowed)
				(copperpour not_allowed)
				(footprints allowed)
			)
			(placement
				(enabled no)
				(sheetname "")
			)
			(fill
				(thermal_gap 0.5)
				(thermal_bridge_width 0.5)
				(island_removal_mode 0)
			)
			(polygon
				(pts
					(xy 178.24323 -115.965986) (xy 178.301396 -115.874546) (xy 178.301396 -115.675156) (xy 178.24323 -115.584986)
					(xy 178.06797 -115.584986) (xy 178.00955 -115.675156) (xy 178.00955 -115.874546) (xy 178.067716 -115.965986)
				)
			)
		)
	)
	(footprint ""
		(layer "B.Cu")
		(at 160.83788 -109.489748)
		(property "Reference" "R1440"
			(at 0 0 0)
			(layer "B.SilkS")
			(hide yes)
			(effects
				(font
					(size 1.27 1.27)
				)
				(justify mirror)
			)
		)
		(property "Value" ""
			(at 0 0 0)
			(layer "B.Fab")
			(effects
				(font
					(size 1.27 1.27)
				)
				(justify mirror)
			)
		)
		(duplicate_pad_numbers_are_jumpers no)
		(fp_line
			(start -0.7874 -0.4064)
			(end -0.7874 0.4064)
			(stroke
				(width 0.1524)
				(type default)
			)
			(layer "B.SilkS")
		)
		(fp_line
			(start -0.7874 0.4064)
			(end 0.7874 0.4064)
			(stroke
				(width 0.1524)
				(type default)
			)
			(layer "B.SilkS")
		)
		(fp_line
			(start 0.7874 -0.4064)
			(end -0.7874 -0.4064)
			(stroke
				(width 0.1524)
				(type default)
			)
			(layer "B.SilkS")
		)
		(fp_line
			(start 0.7874 0.4064)
			(end 0.7874 -0.4064)
			(stroke
				(width 0.1524)
				(type default)
			)
			(layer "B.SilkS")
		)
		(fp_line
			(start -0.67945 -0.3048)
			(end -0.67945 0.3048)
			(stroke
				(width 0.1)
				(type default)
			)
			(layer "B.Fab")
		)
		(fp_line
			(start -0.67945 0.3048)
			(end -0.120396 0.3048)
			(stroke
				(width 0.1)
				(type default)
			)
			(layer "B.Fab")
		)
		(fp_line
			(start -0.12065 -0.3048)
			(end -0.67945 -0.3048)
			(stroke
				(width 0.1)
				(type default)
			)
			(layer "B.Fab")
		)
		(fp_line
			(start -0.12065 -0.2794)
			(end -0.12065 -0.3048)
			(stroke
				(width 0.1)
				(type default)
			)
			(layer "B.Fab")
		)
		(fp_line
			(start -0.120396 0.2794)
			(end 0.12065 0.2794)
			(stroke
				(width 0.1)
				(type default)
			)
			(layer "B.Fab")
		)
		(fp_line
			(start -0.120396 0.3048)
			(end -0.120396 0.2794)
			(stroke
				(width 0.1)
				(type default)
			)
			(layer "B.Fab")
		)
		(fp_line
			(start 0.12065 -0.305054)
			(end 0.12065 -0.2794)
			(stroke
				(width 0.1)
				(type default)
			)
			(layer "B.Fab")
		)
		(fp_line
			(start 0.12065 -0.2794)
			(end -0.12065 -0.2794)
			(stroke
				(width 0.1)
				(type default)
			)
			(layer "B.Fab")
		)
		(fp_line
			(start 0.12065 0.2794)
			(end 0.12065 0.3048)
			(stroke
				(width 0.1)
				(type default)
			)
			(layer "B.Fab")
		)
		(fp_line
			(start 0.12065 0.3048)
			(end 0.67945 0.3048)
			(stroke
				(width 0.1)
				(type default)
			)
			(layer "B.Fab")
		)
		(fp_line
			(start 0.67945 -0.305054)
			(end 0.12065 -0.305054)
			(stroke
				(width 0.1)
				(type default)
			)
			(layer "B.Fab")
		)
		(fp_line
			(start 0.67945 0.3048)
			(end 0.67945 -0.305054)
			(stroke
				(width 0.1)
				(type default)
			)
			(layer "B.Fab")
		)
		(pad "1" smd circle
			(at 0.40005 0 180)
			(size 0 0)
			(layers "B.Cu" "B.Mask" "B.Paste")
			(net "JTAG_PLD_TDO_R")
		)
		(pad "2" smd circle
			(at -0.40005 0 180)
			(size 0 0)
			(layers "B.Cu" "B.Mask" "B.Paste")
			(net "P3V3_AUX")
		)
	)
)
